(kicad_pcb
	(version 20260206)
	(generator "pcbnew")
	(generator_version "10.0")
	(general
		(thickness 1.6)
		(legacy_teardrops no)
	)
	(paper "A4")
	(title_block
		(title "panther-plus-userver — 13130-1b_20150205.brd")
		(comment 1 "Honey Badger (Wiwynn) / footprints 620-623 of 1509")
	)
	(layers
		(0 "F.Cu" signal "TOP")
		(4 "In1.Cu" signal "L2")
		(6 "In2.Cu" signal "L3")
		(8 "In3.Cu" signal "L4")
		(10 "In4.Cu" signal "L5")
		(12 "In5.Cu" signal "L6")
		(14 "In6.Cu" signal "L7")
		(16 "In7.Cu" signal "L8")
		(18 "In8.Cu" signal "L9")
		(20 "In9.Cu" signal "L10")
		(22 "In10.Cu" signal "L11")
		(2 "B.Cu" signal "BOTTOM")
		(9 "F.Adhes" user "F.Adhesive")
		(11 "B.Adhes" user "B.Adhesive")
		(13 "F.Paste" user "Package Geometry/Pastemask Top")
		(15 "B.Paste" user "Package Geometry/Pastemask Bottom")
		(5 "F.SilkS" user "Ref Des/Silkscreen Top")
		(7 "B.SilkS" user "Ref Des/Silkscreen Bottom")
		(1 "F.Mask" user "Board Geometry/Soldermask Top")
		(3 "B.Mask" user "Board Geometry/Soldermask Bottom")
		(17 "Dwgs.User" user "User.Drawings")
		(19 "Cmts.User" user "User.Comments")
		(21 "Eco1.User" user "User.Eco1")
		(23 "Eco2.User" user "User.Eco2")
		(25 "Edge.Cuts" user "Board Geometry/Outline")
		(27 "Margin" user)
		(31 "F.CrtYd" user "Package Geometry/Place Bound Top")
		(29 "B.CrtYd" user "Package Geometry/Place Bound Bottom")
		(35 "F.Fab" user "Ref Des/Assembly Top")
		(33 "B.Fab" user "Ref Des/Assembly Bottom")
	)
	(footprint ""
		(layer "F.Cu")
		(at 188.341 -45.974)
		(property "Reference" "R220"
			(at 0 0 0)
			(layer "F.SilkS")
			(hide yes)
			(effects
				(font
					(size 1.27 1.27)
				)
			)
		)
		(property "Value" "100R2F-L1-GP-U"
			(at 0.064008 -3.993896 0)
			(unlocked yes)
			(layer "F.Fab")
			(hide yes)
			(effects
				(font
					(size 1.016 1.016)
					(thickness 0.1524)
				)
			)
		)
		(property "Device Type" "R402H14"
			(at 0.064008 -5.517896 0)
			(unlocked yes)
			(layer "F.Fab")
			(hide yes)
			(effects
				(font
					(size 1.016 1.016)
					(thickness 0.1524)
				)
			)
		)
		(duplicate_pad_numbers_are_jumpers no)
		(fp_rect
			(start -0.381 0.8382)
			(end 0.381 -0.8382)
			(stroke
				(width 0)
				(type default)
			)
			(fill no)
			(layer "F.CrtYd")
		)
		(fp_rect
			(start -0.381 0.8382)
			(end 0.381 -0.8382)
			(stroke
				(width 0)
				(type default)
			)
			(fill no)
			(layer "F.Fab")
		)
		(pad "1" smd custom
			(at 0 -0.4318)
			(size 0.127 0.127)
			(layers "F.Cu" "F.Mask" "F.Paste")
			(net "PV_VDDR_VREF_B_FB")
			(options
				(clearance outline)
				(anchor circle)
			)
			(primitives
				(gr_poly
					(pts
						(arc
							(start -0.2032 -0.2794)
							(mid -0.239121 -0.264521)
							(end -0.254 -0.2286)
						)
						(arc
							(start -0.254 0.2286)
							(mid -0.239121 0.264521)
							(end -0.2032 0.2794)
						)
						(arc
							(start 0.2032 0.2794)
							(mid 0.239121 0.264521)
							(end 0.254 0.2286)
						)
						(arc
							(start 0.254 -0.2286)
							(mid 0.239121 -0.264521)
							(end 0.2032 -0.2794)
						)
					)
					(width 0)
					(fill yes)
				)
			)
		)
		(pad "2" smd custom
			(at 0 0.4318)
			(size 0.127 0.127)
			(layers "F.Cu" "F.Mask" "F.Paste")
			(net "GND")
			(options
				(clearance outline)
				(anchor circle)
			)
			(primitives
				(gr_poly
					(pts
						(arc
							(start -0.2032 -0.2794)
							(mid -0.239121 -0.264521)
							(end -0.254 -0.2286)
						)
						(arc
							(start -0.254 0.2286)
							(mid -0.239121 0.264521)
							(end -0.2032 0.2794)
						)
						(arc
							(start 0.2032 0.2794)
							(mid 0.239121 0.264521)
							(end 0.254 0.2286)
						)
						(arc
							(start 0.254 -0.2286)
							(mid 0.239121 -0.264521)
							(end 0.2032 -0.2794)
						)
					)
					(width 0)
					(fill yes)
				)
			)
		)
	)
	(footprint ""
		(layer "F.Cu")
		(at 53.848 -12.827)
		(property "Reference" "R412"
			(at 0 0 0)
			(layer "F.SilkS")
			(hide yes)
			(effects
				(font
					(size 1.27 1.27)
				)
			)
		)
		(property "Value" "0R2J-2-GP"
			(at 1.7907 -1.1176 0)
			(unlocked yes)
			(layer "F.Fab")
			(hide yes)
			(effects
				(font
					(size 1.016 1.016)
					(thickness 0.1524)
				)
			)
		)
		(property "Device Type" "R402H16"
			(at 1.7907 -2.6416 0)
			(unlocked yes)
			(layer "F.Fab")
			(hide yes)
			(effects
				(font
					(size 1.016 1.016)
					(thickness 0.1524)
				)
			)
		)
		(duplicate_pad_numbers_are_jumpers no)
		(fp_rect
			(start -0.381 0.8382)
			(end 0.381 -0.8382)
			(stroke
				(width 0)
				(type default)
			)
			(fill no)
			(layer "F.CrtYd")
		)
		(fp_rect
			(start -0.381 0.8382)
			(end 0.381 -0.8382)
			(stroke
				(width 0)
				(type default)
			)
			(fill no)
			(layer "F.Fab")
		)
		(pad "1" smd custom
			(at 0 -0.4318)
			(size 0.127 0.127)
			(layers "F.Cu" "F.Mask" "F.Paste")
			(net "GF_GBE_SMBALRT#")
			(options
				(clearance outline)
				(anchor circle)
			)
			(primitives
				(gr_poly
					(pts
						(arc
							(start -0.2032 -0.2794)
							(mid -0.239121 -0.264521)
							(end -0.254 -0.2286)
						)
						(arc
							(start -0.254 0.2286)
							(mid -0.239121 0.264521)
							(end -0.2032 0.2794)
						)
						(arc
							(start 0.2032 0.2794)
							(mid 0.239121 0.264521)
							(end 0.254 0.2286)
						)
						(arc
							(start 0.254 -0.2286)
							(mid 0.239121 -0.264521)
							(end 0.2032 -0.2794)
						)
					)
					(width 0)
					(fill yes)
				)
			)
		)
		(pad "2" smd custom
			(at 0 0.4318)
			(size 0.127 0.127)
			(layers "F.Cu" "F.Mask" "F.Paste")
			(net "GBE_R_SMBALRT#")
			(options
				(clearance outline)
				(anchor circle)
			)
			(primitives
				(gr_poly
					(pts
						(arc
							(start -0.2032 -0.2794)
							(mid -0.239121 -0.264521)
							(end -0.254 -0.2286)
						)
						(arc
							(start -0.254 0.2286)
							(mid -0.239121 0.264521)
							(end -0.2032 0.2794)
						)
						(arc
							(start 0.2032 0.2794)
							(mid 0.239121 0.264521)
							(end 0.254 0.2286)
						)
						(arc
							(start 0.254 -0.2286)
							(mid 0.239121 -0.264521)
							(end 0.2032 -0.2794)
						)
					)
					(width 0)
					(fill yes)
				)
			)
		)
	)
	(footprint ""
		(layer "F.Cu")
		(at 28.7274 -59.9948)
		(property "Reference" "PR85"
			(at 0 0 0)
			(layer "F.SilkS")
			(hide yes)
			(effects
				(font
					(size 1.27 1.27)
				)
			)
		)
		(property "Value" "0R2J-2-GP"
			(at 1.7907 -1.1176 0)
			(unlocked yes)
			(layer "F.Fab")
			(hide yes)
			(effects
				(font
					(size 1.016 1.016)
					(thickness 0.1524)
				)
			)
		)
		(property "Device Type" "R402H16"
			(at 1.7907 -2.6416 0)
			(unlocked yes)
			(layer "F.Fab")
			(hide yes)
			(effects
				(font
					(size 1.016 1.016)
					(thickness 0.1524)
				)
			)
		)
		(duplicate_pad_numbers_are_jumpers no)
		(fp_rect
			(start -0.381 0.8382)
			(end 0.381 -0.8382)
			(stroke
				(width 0)
				(type default)
			)
			(fill no)
			(layer "F.CrtYd")
		)
		(fp_rect
			(start -0.381 0.8382)
			(end 0.381 -0.8382)
			(stroke
				(width 0)
				(type default)
			)
			(fill no)
			(layer "F.Fab")
		)
		(pad "1" smd custom
			(at 0 -0.4318)
			(size 0.127 0.127)
			(layers "F.Cu" "F.Mask" "F.Paste")
			(net "VCCP_5VBIAS")
			(options
				(clearance outline)
				(anchor circle)
			)
			(primitives
				(gr_poly
					(pts
						(arc
							(start -0.2032 -0.2794)
							(mid -0.239121 -0.264521)
							(end -0.254 -0.2286)
						)
						(arc
							(start -0.254 0.2286)
							(mid -0.239121 0.264521)
							(end -0.2032 0.2794)
						)
						(arc
							(start 0.2032 0.2794)
							(mid 0.239121 0.264521)
							(end 0.254 0.2286)
						)
						(arc
							(start 0.254 -0.2286)
							(mid 0.239121 -0.264521)
							(end 0.2032 -0.2794)
						)
					)
					(width 0)
					(fill yes)
				)
			)
		)
		(pad "2" smd custom
			(at 0 0.4318)
			(size 0.127 0.127)
			(layers "F.Cu" "F.Mask" "F.Paste")
			(net "VR_PVCCP_PVNN_VDD")
			(options
				(clearance outline)
				(anchor circle)
			)
			(primitives
				(gr_poly
					(pts
						(arc
							(start -0.2032 -0.2794)
							(mid -0.239121 -0.264521)
							(end -0.254 -0.2286)
						)
						(arc
							(start -0.254 0.2286)
							(mid -0.239121 0.264521)
							(end -0.2032 0.2794)
						)
						(arc
							(start 0.2032 0.2794)
							(mid 0.239121 0.264521)
							(end 0.254 0.2286)
						)
						(arc
							(start 0.254 -0.2286)
							(mid 0.239121 -0.264521)
							(end 0.2032 -0.2794)
						)
					)
					(width 0)
					(fill yes)
				)
			)
		)
	)
	(footprint ""
		(layer "F.Cu")
		(at 71.247 -14.986 90)
		(property "Reference" "R464"
			(at 0 0 90)
			(layer "F.SilkS")
			(hide yes)
			(effects
				(font
					(size 1.27 1.27)
				)
			)
		)
		(property "Value" "4K7R2F-GP"
			(at 1.7907 -1.1176 90)
			(unlocked yes)
			(layer "F.Fab")
			(hide yes)
			(effects
				(font
					(size 1.016 1.016)
					(thickness 0.1524)
				)
			)
		)
		(property "Device Type" "R402H16"
			(at 1.7907 -2.6416 90)
			(unlocked yes)
			(layer "F.Fab")
			(hide yes)
			(effects
				(font
					(size 1.016 1.016)
					(thickness 0.1524)
				)
			)
		)
		(duplicate_pad_numbers_are_jumpers no)
		(fp_rect
			(start -0.381 0.8382)
			(end 0.381 -0.8382)
			(stroke
				(width 0)
				(type default)
			)
			(fill no)
			(layer "F.CrtYd")
		)
		(fp_rect
			(start -0.381 0.8382)
			(end 0.381 -0.8382)
			(stroke
				(width 0)
				(type default)
			)
			(fill no)
			(layer "F.Fab")
		)
		(pad "1" smd custom
			(at 0 -0.4318 90)
			(size 0.127 0.127)
			(layers "F.Cu" "F.Mask" "F.Paste")
			(net "P3V3_STBY")
			(options
				(clearance outline)
				(anchor circle)
			)
			(primitives
				(gr_poly
					(pts
						(arc
							(start -0.2032 -0.2794)
							(mid -0.239121 -0.264521)
							(end -0.254 -0.2286)
						)
						(arc
							(start -0.254 0.2286)
							(mid -0.239121 0.264521)
							(end -0.2032 0.2794)
						)
						(arc
							(start 0.2032 0.2794)
							(mid 0.239121 0.264521)
							(end 0.254 0.2286)
						)
						(arc
							(start 0.254 -0.2286)
							(mid 0.239121 -0.264521)
							(end 0.2032 -0.2794)
						)
					)
					(width 0)
					(fill yes)
				)
			)
		)
		(pad "2" smd custom
			(at 0 0.4318 90)
			(size 0.127 0.127)
			(layers "F.Cu" "F.Mask" "F.Paste")
			(net "PCIE_GF_I2C_ALERT#")
			(options
				(clearance outline)
				(anchor circle)
			)
			(primitives
				(gr_poly
					(pts
						(arc
							(start -0.2032 -0.2794)
							(mid -0.239121 -0.264521)
							(end -0.254 -0.2286)
						)
						(arc
							(start -0.254 0.2286)
							(mid -0.239121 0.264521)
							(end -0.2032 0.2794)
						)
						(arc
							(start 0.2032 0.2794)
							(mid 0.239121 0.264521)
							(end 0.254 0.2286)
						)
						(arc
							(start 0.254 -0.2286)
							(mid 0.239121 -0.264521)
							(end 0.2032 -0.2794)
						)
					)
					(width 0)
					(fill yes)
				)
			)
		)
	)
)
